# T6G (Grand Teton) — schematic netlist excerpt (pin names and nets, part order shuffled) for the footprints in the layout excerpt that follows; sources: Cadence DE-HDL packaged netlist, KiCad conversion of 04192023_DAF0TMB3IC0_F0TG_MB_C_brd_V02_OCP.brd

R2802  Q_RES  0 5% CHIP  pkg 0402LF  page 240 : A = HPDB_HSC_PWRGD_R ; B = HPDB_HSC_PWRGD
C6065  Q_CAP  1UF 25V 10% X6S  pkg C0402  page 177 : A = P1V2_AUX ; B = GND

(kicad_pcb
	(version 20260206)
	(generator "pcbnew")
	(generator_version "10.0")
	(general
		(thickness 1.6)
		(legacy_teardrops no)
	)
	(paper "A4")
	(title_block
		(title "04192023_DAF0TMB3IC0_F0TG_MB_C_brd_V02_OCP.brd")
		(comment 1 "Grand Teton / footprints 6020-6021 of 8354")
	)
	(layers
		(0 "F.Cu" signal "TOP")
		(4 "In1.Cu" signal "GND")
		(6 "In2.Cu" signal "IN1")
		(8 "In3.Cu" signal "GND1")
		(10 "In4.Cu" signal "IN2")
		(12 "In5.Cu" signal "GND2")
		(14 "In6.Cu" signal "IN3")
		(16 "In7.Cu" signal "GND3")
		(18 "In8.Cu" signal "VCC")
		(20 "In9.Cu" signal "VCC1")
		(22 "In10.Cu" signal "GND4")
		(24 "In11.Cu" signal "IN4")
		(26 "In12.Cu" signal "GND5")
		(28 "In13.Cu" signal "IN5")
		(30 "In14.Cu" signal "GND6")
		(32 "In15.Cu" signal "IN6")
		(34 "In16.Cu" signal "GND7")
		(2 "B.Cu" signal "BOTTOM")
		(9 "F.Adhes" user "F.Adhesive")
		(11 "B.Adhes" user "B.Adhesive")
		(13 "F.Paste" user "Package Geometry/Pastemask Top")
		(15 "B.Paste" user "Package Geometry/Pastemask Bottom")
		(5 "F.SilkS" user "Ref Des/Silkscreen Top")
		(7 "B.SilkS" user "Ref Des/Silkscreen Bottom")
		(1 "F.Mask" user "Board Geometry/Soldermask Top")
		(3 "B.Mask" user "Board Geometry/Soldermask Bottom")
		(17 "Dwgs.User" user "User.Drawings")
		(19 "Cmts.User" user "User.Comments")
		(21 "Eco1.User" user "User.Eco1")
		(23 "Eco2.User" user "User.Eco2")
		(25 "Edge.Cuts" user "Board Geometry/Outline")
		(27 "Margin" user)
		(31 "F.CrtYd" user "Package Geometry/Place Bound Top")
		(29 "B.CrtYd" user "Package Geometry/Place Bound Bottom")
		(35 "F.Fab" user "Ref Des/Assembly Top")
		(33 "B.Fab" user "Ref Des/Assembly Bottom")
	)
	(footprint ""
		(layer "B.Cu")
		(at 130.702304 -33.019492 -90)
		(property "Reference" "C6065"
			(at 0 0 90)
			(layer "B.SilkS")
			(hide yes)
			(effects
				(font
					(size 1.27 1.27)
				)
				(justify mirror)
			)
		)
		(property "Value" ""
			(at 0 0 90)
			(layer "B.Fab")
			(effects
				(font
					(size 1.27 1.27)
				)
				(justify mirror)
			)
		)
		(duplicate_pad_numbers_are_jumpers no)
		(fp_line
			(start -0.7874 0.4064)
			(end 0.7874 0.4064)
			(stroke
				(width 0.1524)
				(type default)
			)
			(layer "B.SilkS")
		)
		(fp_line
			(start 0.7874 0.4064)
			(end 0.7874 -0.4064)
			(stroke
				(width 0.1524)
				(type default)
			)
			(layer "B.SilkS")
		)
		(fp_line
			(start -0.7874 -0.4064)
			(end -0.7874 0.4064)
			(stroke
				(width 0.1524)
				(type default)
			)
			(layer "B.SilkS")
		)
		(fp_line
			(start 0.7874 -0.4064)
			(end -0.7874 -0.4064)
			(stroke
				(width 0.1524)
				(type default)
			)
			(layer "B.SilkS")
		)
		(fp_line
			(start -0.67945 0.3048)
			(end -0.120396 0.3048)
			(stroke
				(width 0.1)
				(type default)
			)
			(layer "B.Fab")
		)
		(fp_line
			(start -0.120396 0.3048)
			(end -0.120396 0.2794)
			(stroke
				(width 0.1)
				(type default)
			)
			(layer "B.Fab")
		)
		(fp_line
			(start 0.12065 0.3048)
			(end 0.67945 0.3048)
			(stroke
				(width 0.1)
				(type default)
			)
			(layer "B.Fab")
		)
		(fp_line
			(start 0.67945 0.3048)
			(end 0.67945 -0.305054)
			(stroke
				(width 0.1)
				(type default)
			)
			(layer "B.Fab")
		)
		(fp_line
			(start -0.120396 0.2794)
			(end 0.12065 0.2794)
			(stroke
				(width 0.1)
				(type default)
			)
			(layer "B.Fab")
		)
		(fp_line
			(start 0.12065 0.2794)
			(end 0.12065 0.3048)
			(stroke
				(width 0.1)
				(type default)
			)
			(layer "B.Fab")
		)
		(fp_line
			(start -0.12065 -0.2794)
			(end -0.12065 -0.3048)
			(stroke
				(width 0.1)
				(type default)
			)
			(layer "B.Fab")
		)
		(fp_line
			(start 0.12065 -0.2794)
			(end -0.12065 -0.2794)
			(stroke
				(width 0.1)
				(type default)
			)
			(layer "B.Fab")
		)
		(fp_line
			(start -0.67945 -0.3048)
			(end -0.67945 0.3048)
			(stroke
				(width 0.1)
				(type default)
			)
			(layer "B.Fab")
		)
		(fp_line
			(start -0.12065 -0.3048)
			(end -0.67945 -0.3048)
			(stroke
				(width 0.1)
				(type default)
			)
			(layer "B.Fab")
		)
		(fp_line
			(start 0.12065 -0.305054)
			(end 0.12065 -0.2794)
			(stroke
				(width 0.1)
				(type default)
			)
			(layer "B.Fab")
		)
		(fp_line
			(start 0.67945 -0.305054)
			(end 0.12065 -0.305054)
			(stroke
				(width 0.1)
				(type default)
			)
			(layer "B.Fab")
		)
		(pad "1" smd circle
			(at 0.40005 0 90)
			(size 0 0)
			(layers "B.Cu" "B.Mask" "B.Paste")
			(net "P1V2_AUX")
		)
		(pad "2" smd circle
			(at -0.40005 0 90)
			(size 0 0)
			(layers "B.Cu" "B.Mask" "B.Paste")
			(net "GND")
		)
	)
	(footprint ""
		(layer "B.Cu")
		(at 235.660692 -422.849548 90)
		(property "Reference" "R2802"
			(at 0 0 90)
			(layer "B.SilkS")
			(hide yes)
			(effects
				(font
					(size 1.27 1.27)
				)
				(justify mirror)
			)
		)
		(property "Value" ""
			(at 0 0 90)
			(layer "B.Fab")
			(effects
				(font
					(size 1.27 1.27)
				)
				(justify mirror)
			)
		)
		(duplicate_pad_numbers_are_jumpers no)
		(fp_line
			(start 0.7874 -0.4064)
			(end -0.7874 -0.4064)
			(stroke
				(width 0.1524)
				(type default)
			)
			(layer "B.SilkS")
		)
		(fp_line
			(start -0.7874 -0.4064)
			(end -0.7874 0.4064)
			(stroke
				(width 0.1524)
				(type default)
			)
			(layer "B.SilkS")
		)
		(fp_line
			(start 0.7874 0.4064)
			(end 0.7874 -0.4064)
			(stroke
				(width 0.1524)
				(type default)
			)
			(layer "B.SilkS")
		)
		(fp_line
			(start -0.7874 0.4064)
			(end 0.7874 0.4064)
			(stroke
				(width 0.1524)
				(type default)
			)
			(layer "B.SilkS")
		)
		(fp_line
			(start 0.67945 -0.305054)
			(end 0.12065 -0.305054)
			(stroke
				(width 0.1)
				(type default)
			)
			(layer "B.Fab")
		)
		(fp_line
			(start 0.12065 -0.305054)
			(end 0.12065 -0.2794)
			(stroke
				(width 0.1)
				(type default)
			)
			(layer "B.Fab")
		)
		(fp_line
			(start -0.12065 -0.3048)
			(end -0.67945 -0.3048)
			(stroke
				(width 0.1)
				(type default)
			)
			(layer "B.Fab")
		)
		(fp_line
			(start -0.67945 -0.3048)
			(end -0.67945 0.3048)
			(stroke
				(width 0.1)
				(type default)
			)
			(layer "B.Fab")
		)
		(fp_line
			(start 0.12065 -0.2794)
			(end -0.12065 -0.2794)
			(stroke
				(width 0.1)
				(type default)
			)
			(layer "B.Fab")
		)
		(fp_line
			(start -0.12065 -0.2794)
			(end -0.12065 -0.3048)
			(stroke
				(width 0.1)
				(type default)
			)
			(layer "B.Fab")
		)
		(fp_line
			(start 0.12065 0.2794)
			(end 0.12065 0.3048)
			(stroke
				(width 0.1)
				(type default)
			)
			(layer "B.Fab")
		)
		(fp_line
			(start -0.120396 0.2794)
			(end 0.12065 0.2794)
			(stroke
				(width 0.1)
				(type default)
			)
			(layer "B.Fab")
		)
		(fp_line
			(start 0.67945 0.3048)
			(end 0.67945 -0.305054)
			(stroke
				(width 0.1)
				(type default)
			)
			(layer "B.Fab")
		)
		(fp_line
			(start 0.12065 0.3048)
			(end 0.67945 0.3048)
			(stroke
				(width 0.1)
				(type default)
			)
			(layer "B.Fab")
		)
		(fp_line
			(start -0.120396 0.3048)
			(end -0.120396 0.2794)
			(stroke
				(width 0.1)
				(type default)
			)
			(layer "B.Fab")
		)
		(fp_line
			(start -0.67945 0.3048)
			(end -0.120396 0.3048)
			(stroke
				(width 0.1)
				(type default)
			)
			(layer "B.Fab")
		)
		(pad "1" smd circle
			(at 0.40005 0 270)
			(size 0 0)
			(layers "B.Cu" "B.Mask" "B.Paste")
			(net "HPDB_HSC_PWRGD_R")
		)
		(pad "2" smd circle
			(at -0.40005 0 270)
			(size 0 0)
			(layers "B.Cu" "B.Mask" "B.Paste")
			(net "HPDB_HSC_PWRGD")
		)
	)
)
